# S9S_MB_2U (Grand Teton) — schematic netlist excerpt (pin names and nets, part order shuffled) for the footprints in the layout excerpt that follows; sources: Cadence DE-HDL packaged netlist, KiCad conversion of 03242023_DA0F0TMBIJ0_F0T_Motherboard_J_brd_V01_OCP.brd

R3264  Q_RES  0 5% CHIP  pkg 0402LF  page 238 : A = HP_LVC3_OCP_V3_2_R_EN ; B = HP_LVC3_OCP_V3_2_EN
R3448  Q_RES  4.7K 5% EMPTY  pkg 0402LF  page 149 : A = P3V3_AUX ; B = GPU_FPGA_BOOT_EN

(kicad_pcb
	(version 20260206)
	(generator "pcbnew")
	(generator_version "10.0")
	(general
		(thickness 1.6)
		(legacy_teardrops no)
	)
	(paper "A4")
	(title_block
		(title "03242023_DA0F0TMBIJ0_F0T_Motherboard_J_brd_V01_OCP.brd")
		(comment 1 "Grand Teton / footprints 3573-3574 of 6105")
	)
	(layers
		(0 "F.Cu" signal "TOP")
		(4 "In1.Cu" signal "GND")
		(6 "In2.Cu" signal "IN1")
		(8 "In3.Cu" signal "GND1")
		(10 "In4.Cu" signal "IN2")
		(12 "In5.Cu" signal "GND2")
		(14 "In6.Cu" signal "IN3")
		(16 "In7.Cu" signal "GND3")
		(18 "In8.Cu" signal "VCC")
		(20 "In9.Cu" signal "VCC1")
		(22 "In10.Cu" signal "GND4")
		(24 "In11.Cu" signal "IN4")
		(26 "In12.Cu" signal "GND5")
		(28 "In13.Cu" signal "IN5")
		(30 "In14.Cu" signal "GND6")
		(32 "In15.Cu" signal "IN6")
		(34 "In16.Cu" signal "GND7")
		(2 "B.Cu" signal "BOTTOM")
		(9 "F.Adhes" user "F.Adhesive")
		(11 "B.Adhes" user "B.Adhesive")
		(13 "F.Paste" user "Package Geometry/Pastemask Top")
		(15 "B.Paste" user "Package Geometry/Pastemask Bottom")
		(5 "F.SilkS" user "Ref Des/Silkscreen Top")
		(7 "B.SilkS" user "Ref Des/Silkscreen Bottom")
		(1 "F.Mask" user "Board Geometry/Soldermask Top")
		(3 "B.Mask" user "Board Geometry/Soldermask Bottom")
		(17 "Dwgs.User" user "User.Drawings")
		(19 "Cmts.User" user "User.Comments")
		(21 "Eco1.User" user "User.Eco1")
		(23 "Eco2.User" user "User.Eco2")
		(25 "Edge.Cuts" user "Board Geometry/Outline")
		(27 "Margin" user)
		(31 "F.CrtYd" user "Package Geometry/Place Bound Top")
		(29 "B.CrtYd" user "Package Geometry/Place Bound Bottom")
		(35 "F.Fab" user "Ref Des/Assembly Top")
		(33 "B.Fab" user "Ref Des/Assembly Bottom")
	)
	(footprint ""
		(layer "F.Cu")
		(at 163.50488 -437.479948)
		(property "Reference" "R3448"
			(at 0 0 0)
			(layer "F.SilkS")
			(hide yes)
			(effects
				(font
					(size 1.27 1.27)
				)
			)
		)
		(property "Value" ""
			(at 0 0 0)
			(layer "F.Fab")
			(effects
				(font
					(size 1.27 1.27)
				)
			)
		)
		(duplicate_pad_numbers_are_jumpers no)
		(fp_line
			(start -0.7874 -0.4064)
			(end 0.7874 -0.4064)
			(stroke
				(width 0.1524)
				(type default)
			)
			(layer "F.SilkS")
		)
		(fp_line
			(start -0.7874 0.4064)
			(end -0.7874 -0.4064)
			(stroke
				(width 0.1524)
				(type default)
			)
			(layer "F.SilkS")
		)
		(fp_line
			(start 0.7874 -0.4064)
			(end 0.7874 0.4064)
			(stroke
				(width 0.1524)
				(type default)
			)
			(layer "F.SilkS")
		)
		(fp_line
			(start 0.7874 0.4064)
			(end -0.7874 0.4064)
			(stroke
				(width 0.1524)
				(type default)
			)
			(layer "F.SilkS")
		)
		(fp_line
			(start -0.67945 -0.305054)
			(end -0.12065 -0.305054)
			(stroke
				(width 0.1)
				(type default)
			)
			(layer "F.Fab")
		)
		(fp_line
			(start -0.67945 0.3048)
			(end -0.67945 -0.305054)
			(stroke
				(width 0.1)
				(type default)
			)
			(layer "F.Fab")
		)
		(fp_line
			(start -0.12065 -0.305054)
			(end -0.12065 -0.2794)
			(stroke
				(width 0.1)
				(type default)
			)
			(layer "F.Fab")
		)
		(fp_line
			(start -0.12065 -0.2794)
			(end 0.12065 -0.2794)
			(stroke
				(width 0.1)
				(type default)
			)
			(layer "F.Fab")
		)
		(fp_line
			(start -0.12065 0.2794)
			(end -0.12065 0.3048)
			(stroke
				(width 0.1)
				(type default)
			)
			(layer "F.Fab")
		)
		(fp_line
			(start -0.12065 0.3048)
			(end -0.67945 0.3048)
			(stroke
				(width 0.1)
				(type default)
			)
			(layer "F.Fab")
		)
		(fp_line
			(start 0.120396 0.2794)
			(end -0.12065 0.2794)
			(stroke
				(width 0.1)
				(type default)
			)
			(layer "F.Fab")
		)
		(fp_line
			(start 0.120396 0.3048)
			(end 0.120396 0.2794)
			(stroke
				(width 0.1)
				(type default)
			)
			(layer "F.Fab")
		)
		(fp_line
			(start 0.12065 -0.3048)
			(end 0.67945 -0.3048)
			(stroke
				(width 0.1)
				(type default)
			)
			(layer "F.Fab")
		)
		(fp_line
			(start 0.12065 -0.2794)
			(end 0.12065 -0.3048)
			(stroke
				(width 0.1)
				(type default)
			)
			(layer "F.Fab")
		)
		(fp_line
			(start 0.67945 -0.3048)
			(end 0.67945 0.3048)
			(stroke
				(width 0.1)
				(type default)
			)
			(layer "F.Fab")
		)
		(fp_line
			(start 0.67945 0.3048)
			(end 0.120396 0.3048)
			(stroke
				(width 0.1)
				(type default)
			)
			(layer "F.Fab")
		)
		(pad "1" smd circle
			(at -0.40005 0)
			(size 0 0)
			(layers "F.Cu" "F.Mask" "F.Paste")
			(net "P3V3_AUX")
		)
		(pad "2" smd circle
			(at 0.40005 0)
			(size 0 0)
			(layers "F.Cu" "F.Mask" "F.Paste")
			(net "GPU_FPGA_BOOT_EN")
		)
	)
	(footprint ""
		(layer "F.Cu")
		(at 98.33864 -33.736788 180)
		(property "Reference" "R3264"
			(at 0 0 180)
			(layer "F.SilkS")
			(hide yes)
			(effects
				(font
					(size 1.27 1.27)
				)
			)
		)
		(property "Value" ""
			(at 0 0 180)
			(layer "F.Fab")
			(effects
				(font
					(size 1.27 1.27)
				)
			)
		)
		(duplicate_pad_numbers_are_jumpers no)
		(fp_line
			(start 0.7874 0.4064)
			(end -0.7874 0.4064)
			(stroke
				(width 0.1524)
				(type default)
			)
			(layer "F.SilkS")
		)
		(fp_line
			(start 0.7874 -0.4064)
			(end 0.7874 0.4064)
			(stroke
				(width 0.1524)
				(type default)
			)
			(layer "F.SilkS")
		)
		(fp_line
			(start -0.7874 0.4064)
			(end -0.7874 -0.4064)
			(stroke
				(width 0.1524)
				(type default)
			)
			(layer "F.SilkS")
		)
		(fp_line
			(start -0.7874 -0.4064)
			(end 0.7874 -0.4064)
			(stroke
				(width 0.1524)
				(type default)
			)
			(layer "F.SilkS")
		)
		(fp_line
			(start 0.67945 0.3048)
			(end 0.120396 0.3048)
			(stroke
				(width 0.1)
				(type default)
			)
			(layer "F.Fab")
		)
		(fp_line
			(start 0.67945 -0.3048)
			(end 0.67945 0.3048)
			(stroke
				(width 0.1)
				(type default)
			)
			(layer "F.Fab")
		)
		(fp_line
			(start 0.12065 -0.2794)
			(end 0.12065 -0.3048)
			(stroke
				(width 0.1)
				(type default)
			)
			(layer "F.Fab")
		)
		(fp_line
			(start 0.12065 -0.3048)
			(end 0.67945 -0.3048)
			(stroke
				(width 0.1)
				(type default)
			)
			(layer "F.Fab")
		)
		(fp_line
			(start 0.120396 0.3048)
			(end 0.120396 0.2794)
			(stroke
				(width 0.1)
				(type default)
			)
			(layer "F.Fab")
		)
		(fp_line
			(start 0.120396 0.2794)
			(end -0.12065 0.2794)
			(stroke
				(width 0.1)
				(type default)
			)
			(layer "F.Fab")
		)
		(fp_line
			(start -0.12065 0.3048)
			(end -0.67945 0.3048)
			(stroke
				(width 0.1)
				(type default)
			)
			(layer "F.Fab")
		)
		(fp_line
			(start -0.12065 0.2794)
			(end -0.12065 0.3048)
			(stroke
				(width 0.1)
				(type default)
			)
			(layer "F.Fab")
		)
		(fp_line
			(start -0.12065 -0.2794)
			(end 0.12065 -0.2794)
			(stroke
				(width 0.1)
				(type default)
			)
			(layer "F.Fab")
		)
		(fp_line
			(start -0.12065 -0.305054)
			(end -0.12065 -0.2794)
			(stroke
				(width 0.1)
				(type default)
			)
			(layer "F.Fab")
		)
		(fp_line
			(start -0.67945 0.3048)
			(end -0.67945 -0.305054)
			(stroke
				(width 0.1)
				(type default)
			)
			(layer "F.Fab")
		)
		(fp_line
			(start -0.67945 -0.305054)
			(end -0.12065 -0.305054)
			(stroke
				(width 0.1)
				(type default)
			)
			(layer "F.Fab")
		)
		(pad "1" smd circle
			(at -0.40005 0 180)
			(size 0 0)
			(layers "F.Cu" "F.Mask" "F.Paste")
			(net "HP_LVC3_OCP_V3_2_R_EN")
		)
		(pad "2" smd circle
			(at 0.40005 0 180)
			(size 0 0)
			(layers "F.Cu" "F.Mask" "F.Paste")
			(net "HP_LVC3_OCP_V3_2_EN")
		)
	)
)
